(kicad_pcb
	(version 20260206)
	(generator "pcbnew")
	(generator_version "10.0")
	(general
		(thickness 1.6)
		(legacy_teardrops no)
	)
	(paper "A4")
	(title_block
		(title "fcb — 12433-1M.1206WZS1330.brd")
		(comment 1 "Open Vault / Knox (Wiwynn) / footprints 276-282 of 495")
	)
	(layers
		(0 "F.Cu" signal "TOP")
		(4 "In1.Cu" signal "L2GND")
		(6 "In2.Cu" signal "L3VCC")
		(2 "B.Cu" signal "BOTTOM")
		(9 "F.Adhes" user "F.Adhesive")
		(11 "B.Adhes" user "B.Adhesive")
		(13 "F.Paste" user "Package Geometry/Pastemask Top")
		(15 "B.Paste" user "Package Geometry/Pastemask Bottom")
		(5 "F.SilkS" user "Ref Des/Silkscreen Top")
		(7 "B.SilkS" user "Ref Des/Silkscreen Bottom")
		(1 "F.Mask" user "Board Geometry/Soldermask Top")
		(3 "B.Mask" user "Board Geometry/Soldermask Bottom")
		(17 "Dwgs.User" user "User.Drawings")
		(19 "Cmts.User" user "User.Comments")
		(21 "Eco1.User" user "User.Eco1")
		(23 "Eco2.User" user "User.Eco2")
		(25 "Edge.Cuts" user "Board Geometry/Outline")
		(27 "Margin" user)
		(31 "F.CrtYd" user "Package Geometry/Place Bound Top")
		(29 "B.CrtYd" user "Package Geometry/Place Bound Bottom")
		(35 "F.Fab" user "Ref Des/Assembly Top")
		(33 "B.Fab" user "Ref Des/Assembly Bottom")
	)
	(footprint ""
		(layer "F.Cu")
		(at 36.0426 -369.1382 -90)
		(property "Reference" "PR4"
			(at 0 0 270)
			(layer "F.SilkS")
			(hide yes)
			(effects
				(font
					(size 1.27 1.27)
				)
			)
		)
		(property "Value" "49K9R2F-L-GP"
			(at 0.064008 -3.993896 270)
			(unlocked yes)
			(layer "F.Fab")
			(hide yes)
			(effects
				(font
					(size 1.016 1.016)
					(thickness 0.1524)
				)
			)
		)
		(property "Device Type" "R402H16"
			(at 0.064008 -5.517896 270)
			(unlocked yes)
			(layer "F.Fab")
			(hide yes)
			(effects
				(font
					(size 1.016 1.016)
					(thickness 0.1524)
				)
			)
		)
		(duplicate_pad_numbers_are_jumpers no)
		(fp_line
			(start -0.508 -0.9398)
			(end -0.508 0.9398)
			(stroke
				(width 0.1524)
				(type default)
			)
			(layer "F.SilkS")
		)
		(fp_line
			(start 0.508 -0.9398)
			(end -0.508 -0.9398)
			(stroke
				(width 0.1524)
				(type default)
			)
			(layer "F.SilkS")
		)
		(fp_rect
			(start -0.508 0.9398)
			(end 0.508 -0.9398)
			(stroke
				(width 0)
				(type default)
			)
			(fill no)
			(layer "F.CrtYd")
		)
		(fp_rect
			(start -0.508 0.9398)
			(end 0.508 -0.9398)
			(stroke
				(width 0)
				(type default)
			)
			(fill no)
			(layer "F.Fab")
		)
		(pad "1" smd custom
			(at 0 -0.4445 270)
			(size 0.1397 0.1397)
			(layers "F.Cu" "F.Mask" "F.Paste")
			(net "P12V_AUX")
			(options
				(clearance outline)
				(anchor circle)
			)
			(primitives
				(gr_poly
					(pts
						(arc
							(start -0.1778 -0.2794)
							(mid -0.249642 -0.249642)
							(end -0.2794 -0.1778)
						)
						(arc
							(start -0.2794 0.1778)
							(mid -0.249642 0.249642)
							(end -0.1778 0.2794)
						)
						(arc
							(start 0.1778 0.2794)
							(mid 0.249642 0.249642)
							(end 0.2794 0.1778)
						)
						(arc
							(start 0.2794 -0.1778)
							(mid 0.249642 -0.249642)
							(end 0.1778 -0.2794)
						)
					)
					(width 0)
					(fill yes)
				)
			)
		)
		(pad "2" smd custom
			(at 0 0.4445 270)
			(size 0.1397 0.1397)
			(layers "F.Cu" "F.Mask" "F.Paste")
			(net "ADM1276_PWRGD")
			(options
				(clearance outline)
				(anchor circle)
			)
			(primitives
				(gr_poly
					(pts
						(arc
							(start -0.1778 -0.2794)
							(mid -0.249642 -0.249642)
							(end -0.2794 -0.1778)
						)
						(arc
							(start -0.2794 0.1778)
							(mid -0.249642 0.249642)
							(end -0.1778 0.2794)
						)
						(arc
							(start 0.1778 0.2794)
							(mid 0.249642 0.249642)
							(end 0.2794 0.1778)
						)
						(arc
							(start 0.2794 -0.1778)
							(mid 0.249642 -0.249642)
							(end 0.1778 -0.2794)
						)
					)
					(width 0)
					(fill yes)
				)
			)
		)
	)
	(footprint ""
		(layer "F.Cu")
		(at 29.9212 -247.4214)
		(property "Reference" "U5"
			(at 0 0 0)
			(layer "F.SilkS")
			(hide yes)
			(effects
				(font
					(size 1.27 1.27)
				)
			)
		)
		(property "Value" "24LC64T-I-GP"
			(at 0 -12.1412 0)
			(unlocked yes)
			(layer "F.Fab")
			(hide yes)
			(effects
				(font
					(size 1.016 1.016)
					(thickness 0.1524)
				)
			)
		)
		(property "Device Type" "SSOIC8-1H44"
			(at 0 -13.6652 0)
			(unlocked yes)
			(layer "F.Fab")
			(hide yes)
			(effects
				(font
					(size 1.016 1.016)
					(thickness 0.1524)
				)
			)
		)
		(duplicate_pad_numbers_are_jumpers no)
		(fp_line
			(start -1.778 -1.778)
			(end -1.778 2.667)
			(stroke
				(width 0.2032)
				(type default)
			)
			(layer "F.SilkS")
		)
		(fp_line
			(start -1.778 -1.778)
			(end 1.397 -1.778)
			(stroke
				(width 0.2032)
				(type default)
			)
			(layer "F.SilkS")
		)
		(fp_line
			(start -1.778 1.778)
			(end -1.778 3.81)
			(stroke
				(width 0.508)
				(type default)
			)
			(layer "F.SilkS")
		)
		(fp_line
			(start -1.143 0)
			(end -1.778 -0.635)
			(stroke
				(width 0.2032)
				(type default)
			)
			(layer "F.SilkS")
		)
		(fp_line
			(start -1.143 0)
			(end -1.778 0.635)
			(stroke
				(width 0.2032)
				(type default)
			)
			(layer "F.SilkS")
		)
		(fp_line
			(start 1.397 -1.778)
			(end 1.397 1.778)
			(stroke
				(width 0.2032)
				(type default)
			)
			(layer "F.SilkS")
		)
		(fp_line
			(start 1.397 1.778)
			(end -1.778 1.778)
			(stroke
				(width 0.2032)
				(type default)
			)
			(layer "F.SilkS")
		)
		(fp_poly
			(pts
				(xy -2.032 3.81) (xy 2.032 3.81) (xy 2.032 -3.81) (xy -2.032 -3.81)
			)
			(stroke
				(width 0)
				(type default)
			)
			(fill no)
			(layer "F.CrtYd")
		)
		(fp_poly
			(pts
				(xy -2.032 -3.81) (xy 2.032 -3.81) (xy 2.032 3.81) (xy -2.032 3.81)
			)
			(stroke
				(width 0)
				(type default)
			)
			(fill no)
			(layer "F.Fab")
		)
		(pad "1" smd rect
			(at -0.97536 2.8194)
			(size 0.3556 1.524)
			(layers "F.Cu" "F.Mask" "F.Paste")
			(net "FCB_EEPROM_A0")
		)
		(pad "2" smd rect
			(at -0.32512 2.8194)
			(size 0.3556 1.524)
			(layers "F.Cu" "F.Mask" "F.Paste")
			(net "FCB_EEPROM_A1")
		)
		(pad "3" smd rect
			(at 0.32512 2.8194)
			(size 0.3556 1.524)
			(layers "F.Cu" "F.Mask" "F.Paste")
			(net "FCB_EEPROM_A2")
		)
		(pad "4" smd rect
			(at 0.97536 2.8194)
			(size 0.3556 1.524)
			(layers "F.Cu" "F.Mask" "F.Paste")
			(net "GND")
		)
		(pad "5" smd rect
			(at 0.97536 -2.8194)
			(size 0.3556 1.524)
			(layers "F.Cu" "F.Mask" "F.Paste")
			(net "I2C_C_SDA_EEPROM")
		)
		(pad "6" smd rect
			(at 0.32512 -2.8194)
			(size 0.3556 1.524)
			(layers "F.Cu" "F.Mask" "F.Paste")
			(net "I2C_C_SCL_EEPROM")
		)
		(pad "7" smd rect
			(at -0.32512 -2.8194)
			(size 0.3556 1.524)
			(layers "F.Cu" "F.Mask" "F.Paste")
			(net "EEPROM_WP")
		)
		(pad "8" smd rect
			(at -0.97536 -2.8194)
			(size 0.3556 1.524)
			(layers "F.Cu" "F.Mask" "F.Paste")
			(net "P3V3")
		)
	)
	(footprint ""
		(layer "F.Cu")
		(at 34.99231 -167.734234)
		(property "Reference" "R9"
			(at 0 0 0)
			(layer "F.SilkS")
			(hide yes)
			(effects
				(font
					(size 1.27 1.27)
				)
			)
		)
		(property "Value" "100KR2J-1-GP"
			(at 0.064008 -3.993896 0)
			(unlocked yes)
			(layer "F.Fab")
			(hide yes)
			(effects
				(font
					(size 1.016 1.016)
					(thickness 0.1524)
				)
			)
		)
		(property "Device Type" "R402H16"
			(at 0.064008 -5.517896 0)
			(unlocked yes)
			(layer "F.Fab")
			(hide yes)
			(effects
				(font
					(size 1.016 1.016)
					(thickness 0.1524)
				)
			)
		)
		(duplicate_pad_numbers_are_jumpers no)
		(fp_line
			(start -0.508 -0.9398)
			(end -0.508 0.9398)
			(stroke
				(width 0.1524)
				(type default)
			)
			(layer "F.SilkS")
		)
		(fp_line
			(start 0.508 -0.9398)
			(end -0.508 -0.9398)
			(stroke
				(width 0.1524)
				(type default)
			)
			(layer "F.SilkS")
		)
		(fp_rect
			(start -0.508 0.9398)
			(end 0.508 -0.9398)
			(stroke
				(width 0)
				(type default)
			)
			(fill no)
			(layer "F.CrtYd")
		)
		(fp_rect
			(start -0.508 0.9398)
			(end 0.508 -0.9398)
			(stroke
				(width 0)
				(type default)
			)
			(fill no)
			(layer "F.Fab")
		)
		(pad "1" smd custom
			(at 0 -0.4445)
			(size 0.1397 0.1397)
			(layers "F.Cu" "F.Mask" "F.Paste")
			(net "P3V3")
			(options
				(clearance outline)
				(anchor circle)
			)
			(primitives
				(gr_poly
					(pts
						(arc
							(start -0.1778 -0.2794)
							(mid -0.249642 -0.249642)
							(end -0.2794 -0.1778)
						)
						(arc
							(start -0.2794 0.1778)
							(mid -0.249642 0.249642)
							(end -0.1778 0.2794)
						)
						(arc
							(start 0.1778 0.2794)
							(mid 0.249642 0.249642)
							(end 0.2794 0.1778)
						)
						(arc
							(start 0.2794 -0.1778)
							(mid 0.249642 -0.249642)
							(end 0.1778 -0.2794)
						)
					)
					(width 0)
					(fill yes)
				)
			)
		)
		(pad "2" smd custom
			(at 0 0.4445)
			(size 0.1397 0.1397)
			(layers "F.Cu" "F.Mask" "F.Paste")
			(net "NCT7904_ADR")
			(options
				(clearance outline)
				(anchor circle)
			)
			(primitives
				(gr_poly
					(pts
						(arc
							(start -0.1778 -0.2794)
							(mid -0.249642 -0.249642)
							(end -0.2794 -0.1778)
						)
						(arc
							(start -0.2794 0.1778)
							(mid -0.249642 0.249642)
							(end -0.1778 0.2794)
						)
						(arc
							(start 0.1778 0.2794)
							(mid 0.249642 0.249642)
							(end 0.2794 0.1778)
						)
						(arc
							(start 0.2794 -0.1778)
							(mid 0.249642 -0.249642)
							(end 0.1778 -0.2794)
						)
					)
					(width 0)
					(fill yes)
				)
			)
		)
	)
	(footprint ""
		(layer "F.Cu")
		(at 36.068 -378.333 180)
		(property "Reference" "PR26"
			(at 0 0 180)
			(layer "F.SilkS")
			(hide yes)
			(effects
				(font
					(size 1.27 1.27)
				)
			)
		)
		(property "Value" "10R2F-L-GP"
			(at 0.064008 -3.993896 180)
			(unlocked yes)
			(layer "F.Fab")
			(hide yes)
			(effects
				(font
					(size 1.016 1.016)
					(thickness 0.1524)
				)
			)
		)
		(property "Device Type" "R402H14"
			(at 0.064008 -5.517896 180)
			(unlocked yes)
			(layer "F.Fab")
			(hide yes)
			(effects
				(font
					(size 1.016 1.016)
					(thickness 0.1524)
				)
			)
		)
		(duplicate_pad_numbers_are_jumpers no)
		(fp_line
			(start 0.508 -0.9398)
			(end -0.508 -0.9398)
			(stroke
				(width 0.1524)
				(type default)
			)
			(layer "F.SilkS")
		)
		(fp_line
			(start -0.508 -0.9398)
			(end -0.508 0.9398)
			(stroke
				(width 0.1524)
				(type default)
			)
			(layer "F.SilkS")
		)
		(fp_rect
			(start -0.508 0.9398)
			(end 0.508 -0.9398)
			(stroke
				(width 0)
				(type default)
			)
			(fill no)
			(layer "F.CrtYd")
		)
		(fp_rect
			(start -0.508 0.9398)
			(end 0.508 -0.9398)
			(stroke
				(width 0)
				(type default)
			)
			(fill no)
			(layer "F.Fab")
		)
		(pad "1" smd custom
			(at 0 -0.4445 180)
			(size 0.1397 0.1397)
			(layers "F.Cu" "F.Mask" "F.Paste")
			(net "ADM1276_GATE")
			(options
				(clearance outline)
				(anchor circle)
			)
			(primitives
				(gr_poly
					(pts
						(arc
							(start -0.1778 -0.2794)
							(mid -0.249642 -0.249642)
							(end -0.2794 -0.1778)
						)
						(arc
							(start -0.2794 0.1778)
							(mid -0.249642 0.249642)
							(end -0.1778 0.2794)
						)
						(arc
							(start 0.1778 0.2794)
							(mid 0.249642 0.249642)
							(end 0.2794 0.1778)
						)
						(arc
							(start 0.2794 -0.1778)
							(mid 0.249642 -0.249642)
							(end 0.1778 -0.2794)
						)
					)
					(width 0)
					(fill yes)
				)
			)
		)
		(pad "2" smd custom
			(at 0 0.4445 180)
			(size 0.1397 0.1397)
			(layers "F.Cu" "F.Mask" "F.Paste")
			(net "ADM1276_GATE_DRV1")
			(options
				(clearance outline)
				(anchor circle)
			)
			(primitives
				(gr_poly
					(pts
						(arc
							(start -0.1778 -0.2794)
							(mid -0.249642 -0.249642)
							(end -0.2794 -0.1778)
						)
						(arc
							(start -0.2794 0.1778)
							(mid -0.249642 0.249642)
							(end -0.1778 0.2794)
						)
						(arc
							(start 0.1778 0.2794)
							(mid 0.249642 0.249642)
							(end 0.2794 0.1778)
						)
						(arc
							(start 0.2794 -0.1778)
							(mid 0.249642 -0.249642)
							(end 0.1778 -0.2794)
						)
					)
					(width 0)
					(fill yes)
				)
			)
		)
	)
	(footprint ""
		(layer "F.Cu")
		(at 40.513 -252.984)
		(property "Reference" "R129"
			(at 0 0 0)
			(layer "F.SilkS")
			(hide yes)
			(effects
				(font
					(size 1.27 1.27)
				)
			)
		)
		(property "Value" "330R2J-3-GP"
			(at 0.064008 -3.993896 0)
			(unlocked yes)
			(layer "F.Fab")
			(hide yes)
			(effects
				(font
					(size 1.016 1.016)
					(thickness 0.1524)
				)
			)
		)
		(property "Device Type" "R402H16"
			(at 0.064008 -5.517896 0)
			(unlocked yes)
			(layer "F.Fab")
			(hide yes)
			(effects
				(font
					(size 1.016 1.016)
					(thickness 0.1524)
				)
			)
		)
		(duplicate_pad_numbers_are_jumpers no)
		(fp_line
			(start -0.508 -0.9398)
			(end -0.508 0.9398)
			(stroke
				(width 0.1524)
				(type default)
			)
			(layer "F.SilkS")
		)
		(fp_line
			(start 0.508 -0.9398)
			(end -0.508 -0.9398)
			(stroke
				(width 0.1524)
				(type default)
			)
			(layer "F.SilkS")
		)
		(fp_rect
			(start -0.508 0.9398)
			(end 0.508 -0.9398)
			(stroke
				(width 0)
				(type default)
			)
			(fill no)
			(layer "F.CrtYd")
		)
		(fp_rect
			(start -0.508 0.9398)
			(end 0.508 -0.9398)
			(stroke
				(width 0)
				(type default)
			)
			(fill no)
			(layer "F.Fab")
		)
		(pad "1" smd custom
			(at 0 -0.4445)
			(size 0.1397 0.1397)
			(layers "F.Cu" "F.Mask" "F.Paste")
			(net "P3V3")
			(options
				(clearance outline)
				(anchor circle)
			)
			(primitives
				(gr_poly
					(pts
						(arc
							(start -0.1778 -0.2794)
							(mid -0.249642 -0.249642)
							(end -0.2794 -0.1778)
						)
						(arc
							(start -0.2794 0.1778)
							(mid -0.249642 0.249642)
							(end -0.1778 0.2794)
						)
						(arc
							(start 0.1778 0.2794)
							(mid 0.249642 0.249642)
							(end 0.2794 0.1778)
						)
						(arc
							(start 0.2794 -0.1778)
							(mid 0.249642 -0.249642)
							(end 0.1778 -0.2794)
						)
					)
					(width 0)
					(fill yes)
				)
			)
		)
		(pad "2" smd custom
			(at 0 0.4445)
			(size 0.1397 0.1397)
			(layers "F.Cu" "F.Mask" "F.Paste")
			(net "LED_DR_LED5")
			(options
				(clearance outline)
				(anchor circle)
			)
			(primitives
				(gr_poly
					(pts
						(arc
							(start -0.1778 -0.2794)
							(mid -0.249642 -0.249642)
							(end -0.2794 -0.1778)
						)
						(arc
							(start -0.2794 0.1778)
							(mid -0.249642 0.249642)
							(end -0.1778 0.2794)
						)
						(arc
							(start 0.1778 0.2794)
							(mid 0.249642 0.249642)
							(end 0.2794 0.1778)
						)
						(arc
							(start 0.2794 -0.1778)
							(mid 0.249642 -0.249642)
							(end 0.1778 -0.2794)
						)
					)
					(width 0)
					(fill yes)
				)
			)
		)
	)
	(footprint ""
		(layer "F.Cu")
		(at 26.3906 -121.7676)
		(property "Reference" "C258"
			(at 0 0 0)
			(layer "F.SilkS")
			(hide yes)
			(effects
				(font
					(size 1.27 1.27)
				)
			)
		)
		(property "Value" "SC1U25V3KX-1-GP"
			(at 0 -2.8194 0)
			(unlocked yes)
			(layer "F.Fab")
			(hide yes)
			(effects
				(font
					(size 1.016 1.016)
					(thickness 0.1524)
				)
			)
		)
		(property "Device Type" "C603H36"
			(at 0 -4.3434 0)
			(unlocked yes)
			(layer "F.Fab")
			(hide yes)
			(effects
				(font
					(size 1.016 1.016)
					(thickness 0.1524)
				)
			)
		)
		(duplicate_pad_numbers_are_jumpers no)
		(fp_line
			(start 0.508 0)
			(end -0.508 0)
			(stroke
				(width 0.2032)
				(type default)
			)
			(layer "F.SilkS")
		)
		(fp_rect
			(start -0.5842 1.3335)
			(end 0.5842 -1.3335)
			(stroke
				(width 0)
				(type default)
			)
			(fill no)
			(layer "F.CrtYd")
		)
		(fp_rect
			(start -0.5842 1.3335)
			(end 0.5842 -1.3335)
			(stroke
				(width 0)
				(type default)
			)
			(fill no)
			(layer "F.Fab")
		)
		(pad "1" smd custom
			(at 0 -0.762)
			(size 0.2159 0.2159)
			(layers "F.Cu" "F.Mask" "F.Paste")
			(net "P12V")
			(options
				(clearance outline)
				(anchor circle)
			)
			(primitives
				(gr_poly
					(pts
						(arc
							(start -0.3302 -0.4318)
							(mid -0.402042 -0.402042)
							(end -0.4318 -0.3302)
						)
						(arc
							(start -0.4318 0.3302)
							(mid -0.402042 0.402042)
							(end -0.3302 0.4318)
						)
						(arc
							(start 0.3302 0.4318)
							(mid 0.402042 0.402042)
							(end 0.4318 0.3302)
						)
						(arc
							(start 0.4318 -0.3302)
							(mid 0.402042 -0.402042)
							(end 0.3302 -0.4318)
						)
					)
					(width 0)
					(fill yes)
				)
			)
		)
		(pad "2" smd custom
			(at 0 0.762)
			(size 0.2159 0.2159)
			(layers "F.Cu" "F.Mask" "F.Paste")
			(net "GND")
			(options
				(clearance outline)
				(anchor circle)
			)
			(primitives
				(gr_poly
					(pts
						(arc
							(start -0.3302 -0.4318)
							(mid -0.402042 -0.402042)
							(end -0.4318 -0.3302)
						)
						(arc
							(start -0.4318 0.3302)
							(mid -0.402042 0.402042)
							(end -0.3302 0.4318)
						)
						(arc
							(start 0.3302 0.4318)
							(mid 0.402042 0.402042)
							(end 0.4318 0.3302)
						)
						(arc
							(start 0.4318 -0.3302)
							(mid 0.402042 -0.402042)
							(end 0.3302 -0.4318)
						)
					)
					(width 0)
					(fill yes)
				)
			)
		)
	)
	(footprint ""
		(layer "F.Cu")
		(at 5.1562 -416.6108 -90)
		(property "Reference" "R28"
			(at 0 0 270)
			(layer "F.SilkS")
			(hide yes)
			(effects
				(font
					(size 1.27 1.27)
				)
			)
		)
		(property "Value" "0R2J-2-GP"
			(at 0.064008 -3.993896 270)
			(unlocked yes)
			(layer "F.Fab")
			(hide yes)
			(effects
				(font
					(size 1.016 1.016)
					(thickness 0.1524)
				)
			)
		)
		(property "Device Type" "R402H16"
			(at 0.064008 -5.517896 270)
			(unlocked yes)
			(layer "F.Fab")
			(hide yes)
			(effects
				(font
					(size 1.016 1.016)
					(thickness 0.1524)
				)
			)
		)
		(duplicate_pad_numbers_are_jumpers no)
		(fp_line
			(start -0.508 -0.9398)
			(end -0.508 0.9398)
			(stroke
				(width 0.1524)
				(type default)
			)
			(layer "F.SilkS")
		)
		(fp_line
			(start 0.508 -0.9398)
			(end -0.508 -0.9398)
			(stroke
				(width 0.1524)
				(type default)
			)
			(layer "F.SilkS")
		)
		(fp_rect
			(start -0.508 0.9398)
			(end 0.508 -0.9398)
			(stroke
				(width 0)
				(type default)
			)
			(fill no)
			(layer "F.CrtYd")
		)
		(fp_rect
			(start -0.508 0.9398)
			(end 0.508 -0.9398)
			(stroke
				(width 0)
				(type default)
			)
			(fill no)
			(layer "F.Fab")
		)
		(pad "1" smd custom
			(at 0 -0.4445 270)
			(size 0.1397 0.1397)
			(layers "F.Cu" "F.Mask" "F.Paste")
			(net "LED_DR_LED1_K")
			(options
				(clearance outline)
				(anchor circle)
			)
			(primitives
				(gr_poly
					(pts
						(arc
							(start -0.1778 -0.2794)
							(mid -0.249642 -0.249642)
							(end -0.2794 -0.1778)
						)
						(arc
							(start -0.2794 0.1778)
							(mid -0.249642 0.249642)
							(end -0.1778 0.2794)
						)
						(arc
							(start 0.1778 0.2794)
							(mid 0.249642 0.249642)
							(end 0.2794 0.1778)
						)
						(arc
							(start 0.2794 -0.1778)
							(mid 0.249642 -0.249642)
							(end 0.1778 -0.2794)
						)
					)
					(width 0)
					(fill yes)
				)
			)
		)
		(pad "2" smd custom
			(at 0 0.4445 270)
			(size 0.1397 0.1397)
			(layers "F.Cu" "F.Mask" "F.Paste")
			(net "GND")
			(options
				(clearance outline)
				(anchor circle)
			)
			(primitives
				(gr_poly
					(pts
						(arc
							(start -0.1778 -0.2794)
							(mid -0.249642 -0.249642)
							(end -0.2794 -0.1778)
						)
						(arc
							(start -0.2794 0.1778)
							(mid -0.249642 0.249642)
							(end -0.1778 0.2794)
						)
						(arc
							(start 0.1778 0.2794)
							(mid 0.249642 0.249642)
							(end 0.2794 0.1778)
						)
						(arc
							(start 0.2794 -0.1778)
							(mid 0.249642 -0.249642)
							(end 0.1778 -0.2794)
						)
					)
					(width 0)
					(fill yes)
				)
			)
		)
	)
)
